# T6G (Grand Teton) — schematic netlist excerpt (pin names and nets, part order shuffled) for the footprints in the layout excerpt that follows; sources: Cadence DE-HDL packaged netlist, KiCad conversion of 04192023_DAF0TMB3IC0_F0TG_MB_C_brd_V02_OCP.brd

PC256  Q_CAP  2.2UF 10V 10% X6S  pkg C0402  page 211 : A = PVDDCR_CPU0_P1_VCC1 ; B = GND
R584  Q_RES  4.7K 5% EMPTY  pkg 0402LF  page 55 : A = GND ; B = RST_CPU1_RSMRST_N
C878  Q_CAP_DIFFBUS  DIFF BUS_0.22UF 6.3V 20% X6S  pkg C0201  page 64 : \1\ = P5E_CPU0_P3_TX_C_DN<11> ; \2\ = P5E_CPU0_P3_TX_DN<11>

(kicad_pcb
	(version 20260206)
	(generator "pcbnew")
	(generator_version "10.0")
	(general
		(thickness 1.6)
		(legacy_teardrops no)
	)
	(paper "A4")
	(title_block
		(title "04192023_DAF0TMB3IC0_F0TG_MB_C_brd_V02_OCP.brd")
		(comment 1 "Grand Teton / footprints 4338-4340 of 8354")
	)
	(layers
		(0 "F.Cu" signal "TOP")
		(4 "In1.Cu" signal "GND")
		(6 "In2.Cu" signal "IN1")
		(8 "In3.Cu" signal "GND1")
		(10 "In4.Cu" signal "IN2")
		(12 "In5.Cu" signal "GND2")
		(14 "In6.Cu" signal "IN3")
		(16 "In7.Cu" signal "GND3")
		(18 "In8.Cu" signal "VCC")
		(20 "In9.Cu" signal "VCC1")
		(22 "In10.Cu" signal "GND4")
		(24 "In11.Cu" signal "IN4")
		(26 "In12.Cu" signal "GND5")
		(28 "In13.Cu" signal "IN5")
		(30 "In14.Cu" signal "GND6")
		(32 "In15.Cu" signal "IN6")
		(34 "In16.Cu" signal "GND7")
		(2 "B.Cu" signal "BOTTOM")
		(9 "F.Adhes" user "F.Adhesive")
		(11 "B.Adhes" user "B.Adhesive")
		(13 "F.Paste" user "Package Geometry/Pastemask Top")
		(15 "B.Paste" user "Package Geometry/Pastemask Bottom")
		(5 "F.SilkS" user "Ref Des/Silkscreen Top")
		(7 "B.SilkS" user "Ref Des/Silkscreen Bottom")
		(1 "F.Mask" user "Board Geometry/Soldermask Top")
		(3 "B.Mask" user "Board Geometry/Soldermask Bottom")
		(17 "Dwgs.User" user "User.Drawings")
		(19 "Cmts.User" user "User.Comments")
		(21 "Eco1.User" user "User.Eco1")
		(23 "Eco2.User" user "User.Eco2")
		(25 "Edge.Cuts" user "Board Geometry/Outline")
		(27 "Margin" user)
		(31 "F.CrtYd" user "Package Geometry/Place Bound Top")
		(29 "B.CrtYd" user "Package Geometry/Place Bound Bottom")
		(35 "F.Fab" user "Ref Des/Assembly Top")
		(33 "B.Fab" user "Ref Des/Assembly Bottom")
	)
	(footprint ""
		(layer "F.Cu")
		(at 152.849834 -322.731892 180)
		(property "Reference" "R584"
			(at 0 0 180)
			(layer "F.SilkS")
			(hide yes)
			(effects
				(font
					(size 1.27 1.27)
				)
			)
		)
		(property "Value" ""
			(at 0 0 180)
			(layer "F.Fab")
			(effects
				(font
					(size 1.27 1.27)
				)
			)
		)
		(duplicate_pad_numbers_are_jumpers no)
		(fp_line
			(start 0.7874 0.4064)
			(end -0.7874 0.4064)
			(stroke
				(width 0.1524)
				(type default)
			)
			(layer "F.SilkS")
		)
		(fp_line
			(start 0.7874 -0.4064)
			(end 0.7874 0.4064)
			(stroke
				(width 0.1524)
				(type default)
			)
			(layer "F.SilkS")
		)
		(fp_line
			(start -0.7874 0.4064)
			(end -0.7874 -0.4064)
			(stroke
				(width 0.1524)
				(type default)
			)
			(layer "F.SilkS")
		)
		(fp_line
			(start -0.7874 -0.4064)
			(end 0.7874 -0.4064)
			(stroke
				(width 0.1524)
				(type default)
			)
			(layer "F.SilkS")
		)
		(fp_line
			(start 0.67945 0.3048)
			(end 0.120396 0.3048)
			(stroke
				(width 0.1)
				(type default)
			)
			(layer "F.Fab")
		)
		(fp_line
			(start 0.67945 -0.3048)
			(end 0.67945 0.3048)
			(stroke
				(width 0.1)
				(type default)
			)
			(layer "F.Fab")
		)
		(fp_line
			(start 0.12065 -0.2794)
			(end 0.12065 -0.3048)
			(stroke
				(width 0.1)
				(type default)
			)
			(layer "F.Fab")
		)
		(fp_line
			(start 0.12065 -0.3048)
			(end 0.67945 -0.3048)
			(stroke
				(width 0.1)
				(type default)
			)
			(layer "F.Fab")
		)
		(fp_line
			(start 0.120396 0.3048)
			(end 0.120396 0.2794)
			(stroke
				(width 0.1)
				(type default)
			)
			(layer "F.Fab")
		)
		(fp_line
			(start 0.120396 0.2794)
			(end -0.12065 0.2794)
			(stroke
				(width 0.1)
				(type default)
			)
			(layer "F.Fab")
		)
		(fp_line
			(start -0.12065 0.3048)
			(end -0.67945 0.3048)
			(stroke
				(width 0.1)
				(type default)
			)
			(layer "F.Fab")
		)
		(fp_line
			(start -0.12065 0.2794)
			(end -0.12065 0.3048)
			(stroke
				(width 0.1)
				(type default)
			)
			(layer "F.Fab")
		)
		(fp_line
			(start -0.12065 -0.2794)
			(end 0.12065 -0.2794)
			(stroke
				(width 0.1)
				(type default)
			)
			(layer "F.Fab")
		)
		(fp_line
			(start -0.12065 -0.305054)
			(end -0.12065 -0.2794)
			(stroke
				(width 0.1)
				(type default)
			)
			(layer "F.Fab")
		)
		(fp_line
			(start -0.67945 0.3048)
			(end -0.67945 -0.305054)
			(stroke
				(width 0.1)
				(type default)
			)
			(layer "F.Fab")
		)
		(fp_line
			(start -0.67945 -0.305054)
			(end -0.12065 -0.305054)
			(stroke
				(width 0.1)
				(type default)
			)
			(layer "F.Fab")
		)
		(pad "1" smd circle
			(at -0.40005 0 180)
			(size 0 0)
			(layers "F.Cu" "F.Mask" "F.Paste")
			(net "GND")
		)
		(pad "2" smd circle
			(at 0.40005 0 180)
			(size 0 0)
			(layers "F.Cu" "F.Mask" "F.Paste")
			(net "RST_CPU1_RSMRST_N")
		)
	)
	(footprint ""
		(layer "F.Cu")
		(at 387.425692 -381.41783 -90)
		(property "Reference" "C878"
			(at 0 0 270)
			(layer "F.SilkS")
			(hide yes)
			(effects
				(font
					(size 1.27 1.27)
				)
			)
		)
		(property "Value" ""
			(at 0 0 270)
			(layer "F.Fab")
			(effects
				(font
					(size 1.27 1.27)
				)
			)
		)
		(duplicate_pad_numbers_are_jumpers no)
		(fp_line
			(start -0.299974 0.150114)
			(end -0.299974 -0.150114)
			(stroke
				(width 0.1)
				(type default)
			)
			(layer "F.Fab")
		)
		(fp_line
			(start 0.299974 0.150114)
			(end -0.299974 0.150114)
			(stroke
				(width 0.1)
				(type default)
			)
			(layer "F.Fab")
		)
		(fp_line
			(start -0.299974 -0.150114)
			(end 0.299974 -0.150114)
			(stroke
				(width 0.1)
				(type default)
			)
			(layer "F.Fab")
		)
		(fp_line
			(start 0.299974 -0.150114)
			(end 0.299974 0.150114)
			(stroke
				(width 0.1)
				(type default)
			)
			(layer "F.Fab")
		)
		(pad "1" smd rect
			(at -0.2667 0 270)
			(size 0.3048 0.381)
			(layers "F.Cu" "F.Mask" "F.Paste")
			(net "P5E_CPU0_P3_TX_C_DN<11>")
		)
		(pad "2" smd rect
			(at 0.2667 0 270)
			(size 0.3048 0.381)
			(layers "F.Cu" "F.Mask" "F.Paste")
			(net "P5E_CPU0_P3_TX_DN<11>")
		)
	)
	(footprint ""
		(layer "F.Cu")
		(at 85.96757 -180.078634 -90)
		(property "Reference" "PC256"
			(at 0 0 270)
			(layer "F.SilkS")
			(hide yes)
			(effects
				(font
					(size 1.27 1.27)
				)
			)
		)
		(property "Value" ""
			(at 0 0 270)
			(layer "F.Fab")
			(effects
				(font
					(size 1.27 1.27)
				)
			)
		)
		(duplicate_pad_numbers_are_jumpers no)
		(fp_line
			(start -0.7874 0.4064)
			(end -0.7874 -0.4064)
			(stroke
				(width 0.1524)
				(type default)
			)
			(layer "F.SilkS")
		)
		(fp_line
			(start -0.134366 0.4064)
			(end -0.7874 0.4064)
			(stroke
				(width 0.1524)
				(type default)
			)
			(layer "F.SilkS")
		)
		(fp_line
			(start 0.7874 0.4064)
			(end 0.500634 0.4064)
			(stroke
				(width 0.1524)
				(type default)
			)
			(layer "F.SilkS")
		)
		(fp_line
			(start -0.7874 -0.4064)
			(end 0.7874 -0.4064)
			(stroke
				(width 0.1524)
				(type default)
			)
			(layer "F.SilkS")
		)
		(fp_line
			(start 0.7874 -0.4064)
			(end 0.7874 0.4064)
			(stroke
				(width 0.1524)
				(type default)
			)
			(layer "F.SilkS")
		)
		(fp_line
			(start -0.67945 0.3048)
			(end -0.67945 -0.305054)
			(stroke
				(width 0.1)
				(type default)
			)
			(layer "F.Fab")
		)
		(fp_line
			(start -0.12065 0.3048)
			(end -0.67945 0.3048)
			(stroke
				(width 0.1)
				(type default)
			)
			(layer "F.Fab")
		)
		(fp_line
			(start 0.120396 0.3048)
			(end 0.120396 0.2794)
			(stroke
				(width 0.1)
				(type default)
			)
			(layer "F.Fab")
		)
		(fp_line
			(start 0.67945 0.3048)
			(end 0.120396 0.3048)
			(stroke
				(width 0.1)
				(type default)
			)
			(layer "F.Fab")
		)
		(fp_line
			(start -0.12065 0.2794)
			(end -0.12065 0.3048)
			(stroke
				(width 0.1)
				(type default)
			)
			(layer "F.Fab")
		)
		(fp_line
			(start 0.120396 0.2794)
			(end -0.12065 0.2794)
			(stroke
				(width 0.1)
				(type default)
			)
			(layer "F.Fab")
		)
		(fp_line
			(start -0.12065 -0.2794)
			(end 0.12065 -0.2794)
			(stroke
				(width 0.1)
				(type default)
			)
			(layer "F.Fab")
		)
		(fp_line
			(start 0.12065 -0.2794)
			(end 0.12065 -0.3048)
			(stroke
				(width 0.1)
				(type default)
			)
			(layer "F.Fab")
		)
		(fp_line
			(start 0.12065 -0.3048)
			(end 0.67945 -0.3048)
			(stroke
				(width 0.1)
				(type default)
			)
			(layer "F.Fab")
		)
		(fp_line
			(start 0.67945 -0.3048)
			(end 0.67945 0.3048)
			(stroke
				(width 0.1)
				(type default)
			)
			(layer "F.Fab")
		)
		(fp_line
			(start -0.67945 -0.305054)
			(end -0.12065 -0.305054)
			(stroke
				(width 0.1)
				(type default)
			)
			(layer "F.Fab")
		)
		(fp_line
			(start -0.12065 -0.305054)
			(end -0.12065 -0.2794)
			(stroke
				(width 0.1)
				(type default)
			)
			(layer "F.Fab")
		)
		(pad "1" smd circle
			(at -0.40005 0 270)
			(size 0 0)
			(layers "F.Cu" "F.Mask" "F.Paste")
			(net "PVDDCR_CPU0_P1_VCC1")
		)
		(pad "2" smd circle
			(at 0.40005 0 270)
			(size 0 0)
			(layers "F.Cu" "F.Mask" "F.Paste")
			(net "GND")
		)
	)
)
